(kicad_pcb
	(version 20260206)
	(generator "pcbnew")
	(generator_version "10.0")
	(general
		(thickness 1.6)
		(legacy_teardrops no)
	)
	(paper "A4")
	(title_block
		(title "v1-chassis-manager — T6M_CM_d_v01_1031_1645.brd")
		(comment 1 "Open CloudServer (Microsoft) / footprints 1088-1094 of 2512")
	)
	(layers
		(0 "F.Cu" signal "TOP")
		(4 "In1.Cu" signal "GND1")
		(6 "In2.Cu" signal "IN1")
		(8 "In3.Cu" signal "VCC1")
		(10 "In4.Cu" signal "VCC2")
		(12 "In5.Cu" signal "GND2")
		(14 "In6.Cu" signal "IN2")
		(16 "In7.Cu" signal "IN3")
		(18 "In8.Cu" signal "GND3")
		(2 "B.Cu" signal "BOTTOM")
		(9 "F.Adhes" user "F.Adhesive")
		(11 "B.Adhes" user "B.Adhesive")
		(13 "F.Paste" user "Package Geometry/Pastemask Top")
		(15 "B.Paste" user "Package Geometry/Pastemask Bottom")
		(5 "F.SilkS" user "Ref Des/Silkscreen Top")
		(7 "B.SilkS" user "Ref Des/Silkscreen Bottom")
		(1 "F.Mask" user "Board Geometry/Soldermask Top")
		(3 "B.Mask" user "Board Geometry/Soldermask Bottom")
		(17 "Dwgs.User" user "User.Drawings")
		(19 "Cmts.User" user "User.Comments")
		(21 "Eco1.User" user "User.Eco1")
		(23 "Eco2.User" user "User.Eco2")
		(25 "Edge.Cuts" user "Board Geometry/Outline")
		(27 "Margin" user)
		(31 "F.CrtYd" user "Package Geometry/Place Bound Top")
		(29 "B.CrtYd" user "Package Geometry/Place Bound Bottom")
		(35 "F.Fab" user "Ref Des/Assembly Top")
		(33 "B.Fab" user "Ref Des/Assembly Bottom")
	)
	(footprint ""
		(layer "F.Cu")
		(at 59.931808 -149.689058)
		(property "Reference" "R314"
			(at -29.640276 -6.737096 0)
			(unlocked yes)
			(layer "F.SilkS")
			(effects
				(font
					(size 0.7874 0.5842)
					(thickness 0.1524)
				)
			)
		)
		(property "Value" ""
			(at 0 0 0)
			(layer "F.Fab")
			(effects
				(font
					(size 1.27 1.27)
				)
			)
		)
		(duplicate_pad_numbers_are_jumpers no)
		(fp_line
			(start -1.2954 -0.5842)
			(end 1.2954 -0.5842)
			(stroke
				(width 0.1524)
				(type default)
			)
			(layer "F.SilkS")
		)
		(fp_line
			(start -1.2954 0.5842)
			(end -1.2954 -0.5842)
			(stroke
				(width 0.1524)
				(type default)
			)
			(layer "F.SilkS")
		)
		(fp_line
			(start 1.2954 -0.5842)
			(end 1.2954 0.5842)
			(stroke
				(width 0.1524)
				(type default)
			)
			(layer "F.SilkS")
		)
		(fp_line
			(start 1.2954 0.5842)
			(end -1.2954 0.5842)
			(stroke
				(width 0.1524)
				(type default)
			)
			(layer "F.SilkS")
		)
		(fp_poly
			(pts
				(xy 1.143 -0.3556) (xy 1.143 0.3556) (xy 0.8636 0.3556) (xy 0.8636 0.4572) (xy -0.8636 0.4572) (xy -0.8636 0.4318)
				(xy -0.8636 0.3556) (xy -1.143 0.3556) (xy -1.143 -0.3556) (xy -0.8636 -0.3556) (xy -0.8636 -0.4572)
				(xy 0.8636 -0.4572) (xy 0.8636 -0.3556)
			)
			(stroke
				(width 0)
				(type default)
			)
			(fill no)
			(layer "F.CrtYd")
		)
		(pad "1" smd rect
			(at 0.7366 0 90)
			(size 0.7112 0.8128)
			(layers "F.Cu" "F.Mask" "F.Paste")
			(net "BMC_NODE1_DACAV33")
		)
		(pad "2" smd rect
			(at -0.7366 0 90)
			(size 0.7112 0.8128)
			(layers "F.Cu" "F.Mask" "F.Paste")
			(net "P3V3_NODE1")
		)
	)
	(footprint ""
		(layer "F.Cu")
		(at 85.96376 -185.205624 -90)
		(property "Reference" "R954"
			(at -4.198112 2.082292 90)
			(unlocked yes)
			(layer "F.SilkS")
			(effects
				(font
					(size 0.7874 0.5842)
					(thickness 0.1524)
				)
				(justify left)
			)
		)
		(property "Value" ""
			(at 0 0 270)
			(layer "F.Fab")
			(effects
				(font
					(size 1.27 1.27)
				)
			)
		)
		(duplicate_pad_numbers_are_jumpers no)
		(fp_line
			(start -0.7874 0.4064)
			(end -0.7874 -0.4064)
			(stroke
				(width 0.1524)
				(type default)
			)
			(layer "F.SilkS")
		)
		(fp_line
			(start 0.7874 0.4064)
			(end -0.7874 0.4064)
			(stroke
				(width 0.1524)
				(type default)
			)
			(layer "F.SilkS")
		)
		(fp_line
			(start -0.7874 -0.4064)
			(end 0.7874 -0.4064)
			(stroke
				(width 0.1524)
				(type default)
			)
			(layer "F.SilkS")
		)
		(fp_line
			(start 0.7874 -0.4064)
			(end 0.7874 0.4064)
			(stroke
				(width 0.1524)
				(type default)
			)
			(layer "F.SilkS")
		)
		(fp_poly
			(pts
				(xy -0.508 0.2794) (xy -0.508 0.2286) (xy -0.635 0.2286) (xy -0.635 -0.254) (xy -0.5334 -0.254)
				(xy -0.5334 -0.2794) (xy 0.5334 -0.2794) (xy 0.5334 -0.254) (xy 0.635 -0.254) (xy 0.635 0.254) (xy 0.5334 0.254)
				(xy 0.5334 0.2794)
			)
			(stroke
				(width 0)
				(type default)
			)
			(fill no)
			(layer "F.CrtYd")
		)
		(pad "1" smd rect
			(at 0.40005 0 270)
			(size 0.4572 0.508)
			(layers "F.Cu" "F.Mask" "F.Paste")
			(net "UART_T6_NODE4_TXD")
		)
		(pad "2" smd rect
			(at -0.40005 0 270)
			(size 0.4572 0.508)
			(layers "F.Cu" "F.Mask" "F.Paste")
			(net "UART_T6_NODE4_TXD_R")
		)
	)
	(footprint ""
		(layer "F.Cu")
		(at 118.72976 -179.363624 -90)
		(property "Reference" "D17"
			(at -3.294126 -5.75691 90)
			(unlocked yes)
			(layer "F.SilkS")
			(effects
				(font
					(size 0.635 0.4064)
					(thickness 0.1524)
				)
				(justify left)
			)
		)
		(property "Value" ""
			(at 0 0 270)
			(layer "F.Fab")
			(effects
				(font
					(size 1.27 1.27)
				)
			)
		)
		(duplicate_pad_numbers_are_jumpers no)
		(fp_line
			(start -1.3208 0.5588)
			(end -1.3208 -0.5588)
			(stroke
				(width 0.1524)
				(type default)
			)
			(layer "F.SilkS")
		)
		(fp_line
			(start 1.3208 0.5588)
			(end -1.3208 0.5588)
			(stroke
				(width 0.1524)
				(type default)
			)
			(layer "F.SilkS")
		)
		(fp_line
			(start 1.6256 0.5588)
			(end 1.6256 -0.5588)
			(stroke
				(width 0.1524)
				(type default)
			)
			(layer "F.SilkS")
		)
		(fp_line
			(start 1.778 0.5588)
			(end 1.3208 0.5588)
			(stroke
				(width 0.1524)
				(type default)
			)
			(layer "F.SilkS")
		)
		(fp_line
			(start -1.3208 -0.5588)
			(end 1.3208 -0.5588)
			(stroke
				(width 0.1524)
				(type default)
			)
			(layer "F.SilkS")
		)
		(fp_line
			(start 1.3208 -0.5588)
			(end 1.3208 0.5588)
			(stroke
				(width 0.1524)
				(type default)
			)
			(layer "F.SilkS")
		)
		(fp_line
			(start 1.4732 -0.5588)
			(end 1.4732 0.5588)
			(stroke
				(width 0.1524)
				(type default)
			)
			(layer "F.SilkS")
		)
		(fp_line
			(start 1.778 -0.5588)
			(end 1.778 0.5588)
			(stroke
				(width 0.1524)
				(type default)
			)
			(layer "F.SilkS")
		)
		(fp_line
			(start 1.778 -0.5588)
			(end 1.3208 -0.5588)
			(stroke
				(width 0.1524)
				(type default)
			)
			(layer "F.SilkS")
		)
		(fp_rect
			(start -1.1684 0.508)
			(end 1.1684 -0.508)
			(stroke
				(width 0)
				(type default)
			)
			(fill no)
			(layer "F.CrtYd")
		)
		(pad "A" smd rect
			(at -0.750062 0 270)
			(size 0.8128 0.8128)
			(layers "F.Cu" "F.Mask" "F.Paste")
			(net "UART_SW_S2_N")
		)
		(pad "C" smd rect
			(at 0.750062 0 270)
			(size 0.8128 0.8128)
			(layers "F.Cu" "F.Mask" "F.Paste")
			(net "N31328107")
		)
	)
	(footprint ""
		(layer "F.Cu")
		(at 112.179354 -135.306054 -90)
		(property "Reference" "PR68"
			(at -1.955546 -6.042152 90)
			(unlocked yes)
			(layer "F.SilkS")
			(effects
				(font
					(size 0.635 0.4064)
					(thickness 0.1524)
				)
				(justify left)
			)
		)
		(property "Value" ""
			(at 0 0 270)
			(layer "F.Fab")
			(effects
				(font
					(size 1.27 1.27)
				)
			)
		)
		(duplicate_pad_numbers_are_jumpers no)
		(fp_line
			(start -0.7874 0.4064)
			(end -0.7874 -0.4064)
			(stroke
				(width 0.1524)
				(type default)
			)
			(layer "F.SilkS")
		)
		(fp_line
			(start 0.7874 0.4064)
			(end -0.7874 0.4064)
			(stroke
				(width 0.1524)
				(type default)
			)
			(layer "F.SilkS")
		)
		(fp_line
			(start -0.7874 -0.4064)
			(end 0.7874 -0.4064)
			(stroke
				(width 0.1524)
				(type default)
			)
			(layer "F.SilkS")
		)
		(fp_line
			(start 0.7874 -0.4064)
			(end 0.7874 0.4064)
			(stroke
				(width 0.1524)
				(type default)
			)
			(layer "F.SilkS")
		)
		(fp_poly
			(pts
				(xy -0.508 0.2794) (xy -0.508 0.2286) (xy -0.635 0.2286) (xy -0.635 -0.254) (xy -0.5334 -0.254)
				(xy -0.5334 -0.2794) (xy 0.5334 -0.2794) (xy 0.5334 -0.254) (xy 0.635 -0.254) (xy 0.635 0.254) (xy 0.5334 0.254)
				(xy 0.5334 0.2794)
			)
			(stroke
				(width 0)
				(type default)
			)
			(fill no)
			(layer "F.CrtYd")
		)
		(pad "1" smd rect
			(at 0.40005 0 270)
			(size 0.4572 0.508)
			(layers "F.Cu" "F.Mask" "F.Paste")
			(net "VR_PVCCP_NODE1_COMP")
		)
		(pad "2" smd rect
			(at -0.40005 0 270)
			(size 0.4572 0.508)
			(layers "F.Cu" "F.Mask" "F.Paste")
			(net "VR_PVCCP_NODE1_FB")
		)
	)
	(footprint ""
		(layer "F.Cu")
		(at 78.90256 -80.683608 -90)
		(property "Reference" "C85"
			(at 17.592294 -1.189482 90)
			(unlocked yes)
			(layer "F.SilkS")
			(effects
				(font
					(size 0.7874 0.5842)
					(thickness 0.1524)
				)
				(justify left)
			)
		)
		(property "Value" ""
			(at 0 0 270)
			(layer "F.Fab")
			(effects
				(font
					(size 1.27 1.27)
				)
			)
		)
		(duplicate_pad_numbers_are_jumpers no)
		(fp_line
			(start -0.7874 0.4064)
			(end -0.7874 -0.4064)
			(stroke
				(width 0.1524)
				(type default)
			)
			(layer "F.SilkS")
		)
		(fp_line
			(start 0.7874 0.4064)
			(end -0.7874 0.4064)
			(stroke
				(width 0.1524)
				(type default)
			)
			(layer "F.SilkS")
		)
		(fp_line
			(start 0 0.381)
			(end 0 -0.381)
			(stroke
				(width 0.1524)
				(type default)
			)
			(layer "F.SilkS")
		)
		(fp_line
			(start -0.7874 -0.4064)
			(end 0.7874 -0.4064)
			(stroke
				(width 0.1524)
				(type default)
			)
			(layer "F.SilkS")
		)
		(fp_line
			(start 0.7874 -0.4064)
			(end 0.7874 0.4064)
			(stroke
				(width 0.1524)
				(type default)
			)
			(layer "F.SilkS")
		)
		(fp_poly
			(pts
				(xy -0.5334 0.254) (xy -0.635 0.254) (xy -0.635 0.2286) (xy -0.635 -0.254) (xy -0.5334 -0.254) (xy -0.5334 -0.2794)
				(xy 0.5334 -0.2794) (xy 0.5334 -0.254) (xy 0.635 -0.254) (xy 0.635 0.254) (xy 0.5334 0.254) (xy 0.5334 0.2794)
				(xy -0.508 0.2794) (xy -0.5334 0.2794)
			)
			(stroke
				(width 0)
				(type default)
			)
			(fill no)
			(layer "F.CrtYd")
		)
		(pad "1" smd rect
			(at 0.40005 0 270)
			(size 0.4572 0.508)
			(layers "F.Cu" "F.Mask" "F.Paste")
			(net "PV_VCCP_NODE1")
		)
		(pad "2" smd rect
			(at -0.40005 0 270)
			(size 0.4572 0.508)
			(layers "F.Cu" "F.Mask" "F.Paste")
			(net "GND")
		)
	)
	(footprint ""
		(layer "F.Cu")
		(at 163.712652 -88.84539)
		(property "Reference" "R529"
			(at -0.668274 2.090928 0)
			(unlocked yes)
			(layer "F.SilkS")
			(effects
				(font
					(size 0.7874 0.5842)
					(thickness 0.1524)
				)
				(justify left)
			)
		)
		(property "Value" ""
			(at 0 0 0)
			(layer "F.Fab")
			(effects
				(font
					(size 1.27 1.27)
				)
			)
		)
		(duplicate_pad_numbers_are_jumpers no)
		(fp_line
			(start -0.7874 -0.4064)
			(end 0.7874 -0.4064)
			(stroke
				(width 0.1524)
				(type default)
			)
			(layer "F.SilkS")
		)
		(fp_line
			(start -0.7874 0.4064)
			(end -0.7874 -0.4064)
			(stroke
				(width 0.1524)
				(type default)
			)
			(layer "F.SilkS")
		)
		(fp_line
			(start 0.7874 -0.4064)
			(end 0.7874 0.4064)
			(stroke
				(width 0.1524)
				(type default)
			)
			(layer "F.SilkS")
		)
		(fp_line
			(start 0.7874 0.4064)
			(end -0.7874 0.4064)
			(stroke
				(width 0.1524)
				(type default)
			)
			(layer "F.SilkS")
		)
		(fp_poly
			(pts
				(xy -0.508 0.2794) (xy -0.508 0.2286) (xy -0.635 0.2286) (xy -0.635 -0.254) (xy -0.5334 -0.254)
				(xy -0.5334 -0.2794) (xy 0.5334 -0.2794) (xy 0.5334 -0.254) (xy 0.635 -0.254) (xy 0.635 0.254) (xy 0.5334 0.254)
				(xy 0.5334 0.2794)
			)
			(stroke
				(width 0)
				(type default)
			)
			(fill no)
			(layer "F.CrtYd")
		)
		(pad "1" smd rect
			(at 0.40005 0)
			(size 0.4572 0.508)
			(layers "F.Cu" "F.Mask" "F.Paste")
			(net "P3V3_NODE1")
		)
		(pad "2" smd rect
			(at -0.40005 0)
			(size 0.4572 0.508)
			(layers "F.Cu" "F.Mask" "F.Paste")
			(net "SPI_USB_NODE1_HOLD_L")
		)
	)
	(footprint ""
		(layer "F.Cu")
		(at 144.738852 -146.20875)
		(property "Reference" "R308"
			(at -0.526288 18.560288 0)
			(unlocked yes)
			(layer "F.SilkS")
			(effects
				(font
					(size 0.7874 0.5842)
					(thickness 0.1524)
				)
				(justify left)
			)
		)
		(property "Value" ""
			(at 0 0 0)
			(layer "F.Fab")
			(effects
				(font
					(size 1.27 1.27)
				)
			)
		)
		(duplicate_pad_numbers_are_jumpers no)
		(fp_line
			(start -0.7874 -0.4064)
			(end 0.7874 -0.4064)
			(stroke
				(width 0.1524)
				(type default)
			)
			(layer "F.SilkS")
		)
		(fp_line
			(start -0.7874 0.4064)
			(end -0.7874 -0.4064)
			(stroke
				(width 0.1524)
				(type default)
			)
			(layer "F.SilkS")
		)
		(fp_line
			(start 0.7874 -0.4064)
			(end 0.7874 0.4064)
			(stroke
				(width 0.1524)
				(type default)
			)
			(layer "F.SilkS")
		)
		(fp_line
			(start 0.7874 0.4064)
			(end -0.7874 0.4064)
			(stroke
				(width 0.1524)
				(type default)
			)
			(layer "F.SilkS")
		)
		(fp_poly
			(pts
				(xy -0.508 0.2794) (xy -0.508 0.2286) (xy -0.635 0.2286) (xy -0.635 -0.254) (xy -0.5334 -0.254)
				(xy -0.5334 -0.2794) (xy 0.5334 -0.2794) (xy 0.5334 -0.254) (xy 0.635 -0.254) (xy 0.635 0.254) (xy 0.5334 0.254)
				(xy 0.5334 0.2794)
			)
			(stroke
				(width 0)
				(type default)
			)
			(fill no)
			(layer "F.CrtYd")
		)
		(pad "1" smd rect
			(at 0.40005 0)
			(size 0.4572 0.508)
			(layers "F.Cu" "F.Mask" "F.Paste")
			(net "GND")
		)
		(pad "2" smd rect
			(at -0.40005 0)
			(size 0.4572 0.508)
			(layers "F.Cu" "F.Mask" "F.Paste")
			(net "PCIE_SW_GPIO5")
		)
	)
)
